(kicad_pcb
	(version 20260206)
	(generator "pcbnew")
	(generator_version "10.0")
	(general
		(thickness 1.6)
		(legacy_teardrops no)
	)
	(paper "A4")
	(title_block
		(title "01162023_DA0F0TEBIF0_F0T_Expander_BD_F_brd_V02_OCP.brd")
		(comment 1 "Grand Teton / footprints 3602-3603 of 9728")
	)
	(layers
		(0 "F.Cu" signal "TOP")
		(4 "In1.Cu" signal "GND")
		(6 "In2.Cu" signal "VCC")
		(8 "In3.Cu" signal "VCC1")
		(10 "In4.Cu" signal "GND1")
		(12 "In5.Cu" signal "IN1")
		(14 "In6.Cu" signal "GND2")
		(16 "In7.Cu" signal "IN2")
		(18 "In8.Cu" signal "GND3")
		(20 "In9.Cu" signal "IN3")
		(22 "In10.Cu" signal "GND4")
		(24 "In11.Cu" signal "IN4")
		(26 "In12.Cu" signal "GND5")
		(28 "In13.Cu" signal "IN5")
		(30 "In14.Cu" signal "GND6")
		(32 "In15.Cu" signal "IN6")
		(34 "In16.Cu" signal "GND7")
		(2 "B.Cu" signal "BOTTOM")
		(9 "F.Adhes" user "F.Adhesive")
		(11 "B.Adhes" user "B.Adhesive")
		(13 "F.Paste" user "Package Geometry/Pastemask Top")
		(15 "B.Paste" user "Package Geometry/Pastemask Bottom")
		(5 "F.SilkS" user "Ref Des/Silkscreen Top")
		(7 "B.SilkS" user "Ref Des/Silkscreen Bottom")
		(1 "F.Mask" user "Board Geometry/Soldermask Top")
		(3 "B.Mask" user "Board Geometry/Soldermask Bottom")
		(17 "Dwgs.User" user "User.Drawings")
		(19 "Cmts.User" user "User.Comments")
		(21 "Eco1.User" user "User.Eco1")
		(23 "Eco2.User" user "User.Eco2")
		(25 "Edge.Cuts" user "Board Geometry/Outline")
		(27 "Margin" user)
		(31 "F.CrtYd" user "Package Geometry/Place Bound Top")
		(29 "B.CrtYd" user "Package Geometry/Place Bound Bottom")
		(35 "F.Fab" user "Ref Des/Assembly Top")
		(33 "B.Fab" user "Ref Des/Assembly Bottom")
	)
	(footprint ""
		(layer "F.Cu")
		(at 102.1588 -200.406)
		(property "Reference" "C4446"
			(at 0 0 0)
			(layer "F.SilkS")
			(hide yes)
			(effects
				(font
					(size 1.27 1.27)
				)
			)
		)
		(property "Value" ""
			(at 0 0 0)
			(layer "F.Fab")
			(effects
				(font
					(size 1.27 1.27)
				)
			)
		)
		(duplicate_pad_numbers_are_jumpers no)
		(fp_line
			(start -0.7874 -0.4064)
			(end 0.7874 -0.4064)
			(stroke
				(width 0.1524)
				(type default)
			)
			(layer "F.SilkS")
		)
		(fp_line
			(start -0.7874 0.4064)
			(end -0.7874 -0.4064)
			(stroke
				(width 0.1524)
				(type default)
			)
			(layer "F.SilkS")
		)
		(fp_line
			(start 0.7874 -0.4064)
			(end 0.7874 0.4064)
			(stroke
				(width 0.1524)
				(type default)
			)
			(layer "F.SilkS")
		)
		(fp_line
			(start 0.7874 0.4064)
			(end -0.7874 0.4064)
			(stroke
				(width 0.1524)
				(type default)
			)
			(layer "F.SilkS")
		)
		(fp_line
			(start -0.67945 -0.305054)
			(end -0.12065 -0.305054)
			(stroke
				(width 0.1)
				(type default)
			)
			(layer "F.Fab")
		)
		(fp_line
			(start -0.67945 0.3048)
			(end -0.67945 -0.305054)
			(stroke
				(width 0.1)
				(type default)
			)
			(layer "F.Fab")
		)
		(fp_line
			(start -0.12065 -0.305054)
			(end -0.12065 -0.2794)
			(stroke
				(width 0.1)
				(type default)
			)
			(layer "F.Fab")
		)
		(fp_line
			(start -0.12065 -0.2794)
			(end 0.12065 -0.2794)
			(stroke
				(width 0.1)
				(type default)
			)
			(layer "F.Fab")
		)
		(fp_line
			(start -0.12065 0.2794)
			(end -0.12065 0.3048)
			(stroke
				(width 0.1)
				(type default)
			)
			(layer "F.Fab")
		)
		(fp_line
			(start -0.12065 0.3048)
			(end -0.67945 0.3048)
			(stroke
				(width 0.1)
				(type default)
			)
			(layer "F.Fab")
		)
		(fp_line
			(start 0.120396 0.2794)
			(end -0.12065 0.2794)
			(stroke
				(width 0.1)
				(type default)
			)
			(layer "F.Fab")
		)
		(fp_line
			(start 0.120396 0.3048)
			(end 0.120396 0.2794)
			(stroke
				(width 0.1)
				(type default)
			)
			(layer "F.Fab")
		)
		(fp_line
			(start 0.12065 -0.3048)
			(end 0.67945 -0.3048)
			(stroke
				(width 0.1)
				(type default)
			)
			(layer "F.Fab")
		)
		(fp_line
			(start 0.12065 -0.2794)
			(end 0.12065 -0.3048)
			(stroke
				(width 0.1)
				(type default)
			)
			(layer "F.Fab")
		)
		(fp_line
			(start 0.67945 -0.3048)
			(end 0.67945 0.3048)
			(stroke
				(width 0.1)
				(type default)
			)
			(layer "F.Fab")
		)
		(fp_line
			(start 0.67945 0.3048)
			(end 0.120396 0.3048)
			(stroke
				(width 0.1)
				(type default)
			)
			(layer "F.Fab")
		)
		(pad "1" smd circle
			(at -0.40005 0)
			(size 0 0)
			(layers "F.Cu" "F.Mask" "F.Paste")
			(net "P3V3_AUX")
		)
		(pad "2" smd circle
			(at 0.40005 0)
			(size 0 0)
			(layers "F.Cu" "F.Mask" "F.Paste")
			(net "GND")
		)
	)
	(footprint ""
		(layer "F.Cu")
		(at 323.164708 -26.785062 180)
		(property "Reference" "J41"
			(at 4.551934 -10.961116 90)
			(unlocked yes)
			(layer "F.SilkS")
			(effects
				(font
					(size 0.7874 0.5842)
					(thickness 0.1524)
				)
			)
		)
		(property "Value" ""
			(at 0 0 180)
			(layer "F.Fab")
			(effects
				(font
					(size 1.27 1.27)
				)
			)
		)
		(duplicate_pad_numbers_are_jumpers no)
		(fp_line
			(start 3.150108 12.115038)
			(end 1.529334 12.115038)
			(stroke
				(width 0.1524)
				(type default)
			)
			(layer "F.SilkS")
		)
		(fp_line
			(start 3.074924 12.014962)
			(end 1.632204 12.014962)
			(stroke
				(width 0.1524)
				(type default)
			)
			(layer "F.SilkS")
		)
		(fp_line
			(start 1.632204 -12.014962)
			(end 3.074924 -12.014962)
			(stroke
				(width 0.1524)
				(type default)
			)
			(layer "F.SilkS")
		)
		(fp_line
			(start 1.529334 -12.115038)
			(end 3.150108 -12.115038)
			(stroke
				(width 0.1524)
				(type default)
			)
			(layer "F.SilkS")
		)
		(fp_line
			(start -1.529334 12.115038)
			(end -3.150108 12.115038)
			(stroke
				(width 0.1524)
				(type default)
			)
			(layer "F.SilkS")
		)
		(fp_line
			(start -1.632204 12.014962)
			(end -3.074924 12.014962)
			(stroke
				(width 0.1524)
				(type default)
			)
			(layer "F.SilkS")
		)
		(fp_line
			(start -3.074924 -12.014962)
			(end -1.632204 -12.014962)
			(stroke
				(width 0.1524)
				(type default)
			)
			(layer "F.SilkS")
		)
		(fp_line
			(start -3.150108 -12.115038)
			(end -1.529334 -12.115038)
			(stroke
				(width 0.1524)
				(type default)
			)
			(layer "F.SilkS")
		)
		(fp_poly
			(pts
				(xy 3.360674 -8.78713) (xy 3.783076 -10.054844) (xy 4.628134 -9.209786)
			)
			(stroke
				(width 0)
				(type default)
			)
			(fill yes)
			(layer "F.SilkS")
		)
		(fp_line
			(start 3.074924 12.014962)
			(end -3.074924 12.014962)
			(stroke
				(width 0.1)
				(type default)
			)
			(layer "F.Fab")
		)
		(fp_line
			(start 3.074924 -12.014962)
			(end 3.074924 12.014962)
			(stroke
				(width 0.1)
				(type default)
			)
			(layer "F.Fab")
		)
		(fp_line
			(start -3.074924 12.014962)
			(end -3.074924 -12.014962)
			(stroke
				(width 0.1)
				(type default)
			)
			(layer "F.Fab")
		)
		(fp_line
			(start -3.074924 -12.014962)
			(end 3.074924 -12.014962)
			(stroke
				(width 0.1)
				(type default)
			)
			(layer "F.Fab")
		)
		(fp_poly
			(pts
				(xy 3.348736 -7.994904) (xy 4.543806 -8.592566) (xy 4.543806 -7.397496)
			)
			(stroke
				(width 0)
				(type default)
			)
			(fill yes)
			(layer "F.Fab")
		)
		(pad "" np_thru_hole circle
			(at -1.75006 -9.815068 90)
			(size 1.1176 1.1176)
			(drill 1.1176)
			(layers "*.Cu" "*.Mask")
			(clearance 0.381)
			(thermal_gap 0.381)
		)
		(pad "" np_thru_hole circle
			(at 0 9.815068 90)
			(size 1.1176 1.1176)
			(drill 1.1176)
			(layers "*.Cu" "*.Mask")
			(clearance 0.381)
			(thermal_gap 0.381)
		)
		(pad "A1" smd rect
			(at 2.29997 -7.994904 90)
			(size 0.381 1.27)
			(layers "F.Cu" "F.Mask" "F.Paste")
			(net "GND")
		)
		(pad "A2" smd rect
			(at 2.29997 -7.394956 90)
			(size 0.381 1.27)
			(layers "F.Cu" "F.Mask" "F.Paste")
			(net "GND")
		)
		(pad "A3" smd rect
			(at 2.29997 -6.795008 90)
			(size 0.381 1.27)
			(layers "F.Cu" "F.Mask" "F.Paste")
			(net "GND")
		)
		(pad "A4" smd rect
			(at 2.29997 -6.19506 90)
			(size 0.381 1.27)
			(layers "F.Cu" "F.Mask" "F.Paste")
			(net "GND")
		)
		(pad "A5" smd rect
			(at 2.29997 -5.595112 90)
			(size 0.381 1.27)
			(layers "F.Cu" "F.Mask" "F.Paste")
			(net "GND")
		)
		(pad "A6" smd rect
			(at 2.29997 -4.99491 90)
			(size 0.381 1.27)
			(layers "F.Cu" "F.Mask" "F.Paste")
			(net "GND")
		)
		(pad "A7" smd rect
			(at 2.29997 -4.394962 90)
			(size 0.381 1.27)
			(layers "F.Cu" "F.Mask" "F.Paste")
			(net "SMB_ISO_SSD11_R_SCL")
		)
		(pad "A8" smd rect
			(at 2.29997 -3.795014 90)
			(size 0.381 1.27)
			(layers "F.Cu" "F.Mask" "F.Paste")
			(net "SMB_ISO_SSD11_R_SDA")
		)
		(pad "A9" smd rect
			(at 2.29997 -3.195066 90)
			(size 0.381 1.27)
			(layers "F.Cu" "F.Mask" "F.Paste")
			(net "RST_SMB_SSD11_ISO_R_N")
		)
		(pad "A10" smd rect
			(at 2.29997 -2.595118 90)
			(size 0.381 1.27)
			(layers "F.Cu" "F.Mask" "F.Paste")
			(net "SSD11_LED_ISO_R_N")
		)
		(pad "A11" smd rect
			(at 2.29997 -1.994916 90)
			(size 0.381 1.27)
			(layers "F.Cu" "F.Mask" "F.Paste")
			(net "PU_CLKREQ11")
		)
		(pad "A12" smd rect
			(at 2.29997 -1.394968 90)
			(size 0.381 1.27)
			(layers "F.Cu" "F.Mask" "F.Paste")
			(net "PRSNT_SSD11_N")
		)
		(pad "A13" smd rect
			(at 2.29997 -0.79502 90)
			(size 0.381 1.27)
			(layers "F.Cu" "F.Mask" "F.Paste")
			(net "GND")
		)
		(pad "A14" smd rect
			(at 2.29997 -0.195072 90)
			(size 0.381 1.27)
			(layers "F.Cu" "F.Mask" "F.Paste")
			(net "Net_8483")
		)
		(pad "A15" smd rect
			(at 2.29997 0.404876 90)
			(size 0.381 1.27)
			(layers "F.Cu" "F.Mask" "F.Paste")
			(net "Net_8482")
		)
		(pad "A16" smd rect
			(at 2.29997 1.005078 90)
			(size 0.381 1.27)
			(layers "F.Cu" "F.Mask" "F.Paste")
			(net "GND")
		)
		(pad "A17" smd rect
			(at 2.29997 1.605026 90)
			(size 0.381 1.27)
			(layers "F.Cu" "F.Mask" "F.Paste")
			(net "P5E_PEX2_STN2_RX_DN<32>")
		)
		(pad "A18" smd rect
			(at 2.29997 2.204974 90)
			(size 0.381 1.27)
			(layers "F.Cu" "F.Mask" "F.Paste")
			(net "P5E_PEX2_STN2_RX_DP<32>")
		)
		(pad "A19" smd rect
			(at 2.29997 2.804922 90)
			(size 0.381 1.27)
			(layers "F.Cu" "F.Mask" "F.Paste")
			(net "GND")
		)
		(pad "A20" smd rect
			(at 2.29997 3.405124 90)
			(size 0.381 1.27)
			(layers "F.Cu" "F.Mask" "F.Paste")
			(net "P5E_PEX2_STN2_RX_DN<33>")
		)
		(pad "A21" smd rect
			(at 2.29997 4.005072 90)
			(size 0.381 1.27)
			(layers "F.Cu" "F.Mask" "F.Paste")
			(net "P5E_PEX2_STN2_RX_DP<33>")
		)
		(pad "A22" smd rect
			(at 2.29997 4.60502 90)
			(size 0.381 1.27)
			(layers "F.Cu" "F.Mask" "F.Paste")
			(net "GND")
		)
		(pad "A23" smd rect
			(at 2.29997 5.204968 90)
			(size 0.381 1.27)
			(layers "F.Cu" "F.Mask" "F.Paste")
			(net "P5E_PEX2_STN2_RX_DN<34>")
		)
		(pad "A24" smd rect
			(at 2.29997 5.804916 90)
			(size 0.381 1.27)
			(layers "F.Cu" "F.Mask" "F.Paste")
			(net "P5E_PEX2_STN2_RX_DP<34>")
		)
		(pad "A25" smd rect
			(at 2.29997 6.405118 90)
			(size 0.381 1.27)
			(layers "F.Cu" "F.Mask" "F.Paste")
			(net "GND")
		)
		(pad "A26" smd rect
			(at 2.29997 7.005066 90)
			(size 0.381 1.27)
			(layers "F.Cu" "F.Mask" "F.Paste")
			(net "P5E_PEX2_STN2_RX_DN<35>")
		)
		(pad "A27" smd rect
			(at 2.29997 7.605014 90)
			(size 0.381 1.27)
			(layers "F.Cu" "F.Mask" "F.Paste")
			(net "P5E_PEX2_STN2_RX_DP<35>")
		)
		(pad "A28" smd rect
			(at 2.29997 8.204962 90)
			(size 0.381 1.27)
			(layers "F.Cu" "F.Mask" "F.Paste")
			(net "GND")
		)
		(pad "B1" smd rect
			(at -2.29997 -7.994904 90)
			(size 0.381 1.27)
			(layers "F.Cu" "F.Mask" "F.Paste")
			(net "P12V_SSD11")
		)
		(pad "B2" smd rect
			(at -2.29997 -7.394956 90)
			(size 0.381 1.27)
			(layers "F.Cu" "F.Mask" "F.Paste")
			(net "P12V_SSD11")
		)
		(pad "B3" smd rect
			(at -2.29997 -6.795008 90)
			(size 0.381 1.27)
			(layers "F.Cu" "F.Mask" "F.Paste")
			(net "P12V_SSD11")
		)
		(pad "B4" smd rect
			(at -2.29997 -6.19506 90)
			(size 0.381 1.27)
			(layers "F.Cu" "F.Mask" "F.Paste")
			(net "P12V_SSD11")
		)
		(pad "B5" smd rect
			(at -2.29997 -5.595112 90)
			(size 0.381 1.27)
			(layers "F.Cu" "F.Mask" "F.Paste")
			(net "P12V_SSD11")
		)
		(pad "B6" smd rect
			(at -2.29997 -4.99491 90)
			(size 0.381 1.27)
			(layers "F.Cu" "F.Mask" "F.Paste")
			(net "P12V_SSD11")
		)
		(pad "B7" smd rect
			(at -2.29997 -4.394962 90)
			(size 0.381 1.27)
			(layers "F.Cu" "F.Mask" "F.Paste")
			(net "Net_8484")
		)
		(pad "B8" smd rect
			(at -2.29997 -3.795014 90)
			(size 0.381 1.27)
			(layers "F.Cu" "F.Mask" "F.Paste")
			(net "Net_8481")
		)
		(pad "B9" smd rect
			(at -2.29997 -3.195066 90)
			(size 0.381 1.27)
			(layers "F.Cu" "F.Mask" "F.Paste")
			(net "DUALPORT_N_SSD11")
		)
		(pad "B10" smd rect
			(at -2.29997 -2.595118 90)
			(size 0.381 1.27)
			(layers "F.Cu" "F.Mask" "F.Paste")
			(net "RST_SSD11_PERST_R_N")
		)
		(pad "B11" smd rect
			(at -2.29997 -1.994916 90)
			(size 0.381 1.27)
			(layers "F.Cu" "F.Mask" "F.Paste")
			(net "P3V3_SSD11")
		)
		(pad "B12" smd rect
			(at -2.29997 -1.394968 90)
			(size 0.381 1.27)
			(layers "F.Cu" "F.Mask" "F.Paste")
			(net "SSD11_PWRDIS_R")
		)
		(pad "B13" smd rect
			(at -2.29997 -0.79502 90)
			(size 0.381 1.27)
			(layers "F.Cu" "F.Mask" "F.Paste")
			(net "GND")
		)
		(pad "B14" smd rect
			(at -2.29997 -0.195072 90)
			(size 0.381 1.27)
			(layers "F.Cu" "F.Mask" "F.Paste")
			(net "CLK_100M_DB800ZL_SSD11_R_DN")
		)
		(pad "B15" smd rect
			(at -2.29997 0.404876 90)
			(size 0.381 1.27)
			(layers "F.Cu" "F.Mask" "F.Paste")
			(net "CLK_100M_DB800ZL_SSD11_R_DP")
		)
		(pad "B16" smd rect
			(at -2.29997 1.005078 90)
			(size 0.381 1.27)
			(layers "F.Cu" "F.Mask" "F.Paste")
			(net "GND")
		)
		(pad "B17" smd rect
			(at -2.29997 1.605026 90)
			(size 0.381 1.27)
			(layers "F.Cu" "F.Mask" "F.Paste")
			(net "P5E_PEX2_STN2_TX_C_DN<32>")
		)
		(pad "B18" smd rect
			(at -2.29997 2.204974 90)
			(size 0.381 1.27)
			(layers "F.Cu" "F.Mask" "F.Paste")
			(net "P5E_PEX2_STN2_TX_C_DP<32>")
		)
		(pad "B19" smd rect
			(at -2.29997 2.804922 90)
			(size 0.381 1.27)
			(layers "F.Cu" "F.Mask" "F.Paste")
			(net "GND")
		)
		(pad "B20" smd rect
			(at -2.29997 3.405124 90)
			(size 0.381 1.27)
			(layers "F.Cu" "F.Mask" "F.Paste")
			(net "P5E_PEX2_STN2_TX_C_DN<33>")
		)
		(pad "B21" smd rect
			(at -2.29997 4.005072 90)
			(size 0.381 1.27)
			(layers "F.Cu" "F.Mask" "F.Paste")
			(net "P5E_PEX2_STN2_TX_C_DP<33>")
		)
		(pad "B22" smd rect
			(at -2.29997 4.60502 90)
			(size 0.381 1.27)
			(layers "F.Cu" "F.Mask" "F.Paste")
			(net "GND")
		)
		(pad "B23" smd rect
			(at -2.29997 5.204968 90)
			(size 0.381 1.27)
			(layers "F.Cu" "F.Mask" "F.Paste")
			(net "P5E_PEX2_STN2_TX_C_DN<34>")
		)
		(pad "B24" smd rect
			(at -2.29997 5.804916 90)
			(size 0.381 1.27)
			(layers "F.Cu" "F.Mask" "F.Paste")
			(net "P5E_PEX2_STN2_TX_C_DP<34>")
		)
		(pad "B25" smd rect
			(at -2.29997 6.405118 90)
			(size 0.381 1.27)
			(layers "F.Cu" "F.Mask" "F.Paste")
			(net "GND")
		)
		(pad "B26" smd rect
			(at -2.29997 7.005066 90)
			(size 0.381 1.27)
			(layers "F.Cu" "F.Mask" "F.Paste")
			(net "P5E_PEX2_STN2_TX_C_DN<35>")
		)
		(pad "B27" smd rect
			(at -2.29997 7.605014 90)
			(size 0.381 1.27)
			(layers "F.Cu" "F.Mask" "F.Paste")
			(net "P5E_PEX2_STN2_TX_C_DP<35>")
		)
		(pad "B28" smd rect
			(at -2.29997 8.204962 90)
			(size 0.381 1.27)
			(layers "F.Cu" "F.Mask" "F.Paste")
			(net "GND")
		)
		(pad "G1" thru_hole oval
			(at 0 -11.364976 90)
			(size 1.6256 3.4798)
			(drill oval 1.1176 2.4638)
			(layers "*.Cu" "*.Mask")
			(remove_unused_layers no)
			(net "GND")
			(clearance 0.127)
			(thermal_gap 0.127)
		)
		(pad "G2" thru_hole oval
			(at 0 11.364976 90)
			(size 1.6256 3.4798)
			(drill oval 1.1176 2.4638)
			(layers "*.Cu" "*.Mask")
			(remove_unused_layers no)
			(net "GND")
			(clearance 0.127)
			(thermal_gap 0.127)
		)
		(zone
			(layer "F.Cu")
			(hatch none 0.5)
			(connect_pads
				(clearance 0)
			)
			(min_thickness 0.25)
			(keepout
				(tracks not_allowed)
				(vias allowed)
				(pads allowed)
				(copperpour not_allowed)
				(footprints allowed)
			)
			(placement
				(enabled no)
				(sheetname "")
			)
			(fill
				(thermal_gap 0.5)
				(thermal_bridge_width 0.5)
				(island_removal_mode 0)
			)
			(polygon
				(pts
					(xy 324.54469 -38.850062) (xy 321.794632 -38.850062) (xy 321.794632 -35.900106) (xy 324.54469 -35.900106)
				)
			)
		)
		(zone
			(layer "F.Cu")
			(hatch none 0.5)
			(connect_pads
				(clearance 0)
			)
			(min_thickness 0.25)
			(keepout
				(tracks not_allowed)
				(vias allowed)
				(pads allowed)
				(copperpour not_allowed)
				(footprints allowed)
			)
			(placement
				(enabled no)
				(sheetname "")
			)
			(fill
				(thermal_gap 0.5)
				(thermal_bridge_width 0.5)
				(island_removal_mode 0)
			)
			(polygon
				(pts
					(xy 325.614792 -17.670018) (xy 321.784726 -17.670018) (xy 321.784726 -14.720062) (xy 325.614792 -14.720062)
				)
			)
		)
		(zone
			(layers "F.Cu" "B.Cu" "In1.Cu" "In2.Cu" "In3.Cu" "In4.Cu" "In5.Cu" "In6.Cu"
				"In7.Cu" "In8.Cu" "In9.Cu" "In10.Cu" "In11.Cu" "In12.Cu" "In13.Cu" "In14.Cu"
				"In15.Cu" "In16.Cu"
			)
			(hatch none 0.5)
			(connect_pads
				(clearance 0)
			)
			(min_thickness 0.25)
			(keepout
				(tracks not_allowed)
				(vias allowed)
				(pads allowed)
				(copperpour not_allowed)
				(footprints allowed)
			)
			(placement
				(enabled no)
				(sheetname "")
			)
			(fill
				(thermal_gap 0.5)
				(thermal_bridge_width 0.5)
				(island_removal_mode 0)
			)
			(polygon
				(pts
					(arc
						(start 324.129908 -36.60013)
						(mid 322.199508 -36.60013)
						(end 324.129908 -36.60013)
					)
				)
			)
		)
		(zone
			(layers "F.Cu" "B.Cu" "In1.Cu" "In2.Cu" "In3.Cu" "In4.Cu" "In5.Cu" "In6.Cu"
				"In7.Cu" "In8.Cu" "In9.Cu" "In10.Cu" "In11.Cu" "In12.Cu" "In13.Cu" "In14.Cu"
				"In15.Cu" "In16.Cu"
			)
			(hatch none 0.5)
			(connect_pads
				(clearance 0)
			)
			(min_thickness 0.25)
			(keepout
				(tracks not_allowed)
				(vias allowed)
				(pads allowed)
				(copperpour not_allowed)
				(footprints allowed)
			)
			(placement
				(enabled no)
				(sheetname "")
			)
			(fill
				(thermal_gap 0.5)
				(thermal_bridge_width 0.5)
				(island_removal_mode 0)
			)
			(polygon
				(pts
					(arc
						(start 325.879968 -16.969994)
						(mid 323.949568 -16.969994)
						(end 325.879968 -16.969994)
					)
				)
			)
		)
	)
)
